(kicad_pcb
	(version 20260206)
	(generator "pcbnew")
	(generator_version "10.0")
	(general
		(thickness 1.6)
		(legacy_teardrops no)
	)
	(paper "A4")
	(title_block
		(title "12092022_DA0F0TMDCD0_F0T_Management_Board_D_brd_V3_OCP.brd")
		(comment 1 "Grand Teton / footprints 130-135 of 1440")
	)
	(layers
		(0 "F.Cu" signal "TOP")
		(4 "In1.Cu" signal "GND")
		(6 "In2.Cu" signal "IN1")
		(8 "In3.Cu" signal "GND1")
		(10 "In4.Cu" signal "IN2")
		(12 "In5.Cu" signal "VCC")
		(14 "In6.Cu" signal "VCC1")
		(16 "In7.Cu" signal "IN3")
		(18 "In8.Cu" signal "GND2")
		(20 "In9.Cu" signal "IN4")
		(22 "In10.Cu" signal "GND3")
		(2 "B.Cu" signal "BOTTOM")
		(9 "F.Adhes" user "F.Adhesive")
		(11 "B.Adhes" user "B.Adhesive")
		(13 "F.Paste" user "Package Geometry/Pastemask Top")
		(15 "B.Paste" user "Package Geometry/Pastemask Bottom")
		(5 "F.SilkS" user "Ref Des/Silkscreen Top")
		(7 "B.SilkS" user "Ref Des/Silkscreen Bottom")
		(1 "F.Mask" user "Board Geometry/Soldermask Top")
		(3 "B.Mask" user "Board Geometry/Soldermask Bottom")
		(17 "Dwgs.User" user "User.Drawings")
		(19 "Cmts.User" user "User.Comments")
		(21 "Eco1.User" user "User.Eco1")
		(23 "Eco2.User" user "User.Eco2")
		(25 "Edge.Cuts" user "Board Geometry/Outline")
		(27 "Margin" user)
		(31 "F.CrtYd" user "Package Geometry/Place Bound Top")
		(29 "B.CrtYd" user "Package Geometry/Place Bound Bottom")
		(35 "F.Fab" user "Ref Des/Assembly Top")
		(33 "B.Fab" user "Ref Des/Assembly Bottom")
	)
	(footprint ""
		(layer "F.Cu")
		(at 10.287 -101.854 90)
		(property "Reference" "R517"
			(at 0 0 90)
			(layer "F.SilkS")
			(hide yes)
			(effects
				(font
					(size 1.27 1.27)
				)
			)
		)
		(property "Value" ""
			(at 0 0 90)
			(layer "F.Fab")
			(effects
				(font
					(size 1.27 1.27)
				)
			)
		)
		(duplicate_pad_numbers_are_jumpers no)
		(fp_line
			(start 0.7874 -0.4064)
			(end 0.7874 0.4064)
			(stroke
				(width 0.1524)
				(type default)
			)
			(layer "F.SilkS")
		)
		(fp_line
			(start -0.7874 -0.4064)
			(end 0.7874 -0.4064)
			(stroke
				(width 0.1524)
				(type default)
			)
			(layer "F.SilkS")
		)
		(fp_line
			(start 0.7874 0.4064)
			(end -0.7874 0.4064)
			(stroke
				(width 0.1524)
				(type default)
			)
			(layer "F.SilkS")
		)
		(fp_line
			(start -0.7874 0.4064)
			(end -0.7874 -0.4064)
			(stroke
				(width 0.1524)
				(type default)
			)
			(layer "F.SilkS")
		)
		(fp_line
			(start -0.12065 -0.305054)
			(end -0.12065 -0.2794)
			(stroke
				(width 0.1)
				(type default)
			)
			(layer "F.Fab")
		)
		(fp_line
			(start -0.67945 -0.305054)
			(end -0.12065 -0.305054)
			(stroke
				(width 0.1)
				(type default)
			)
			(layer "F.Fab")
		)
		(fp_line
			(start 0.67945 -0.3048)
			(end 0.67945 0.3048)
			(stroke
				(width 0.1)
				(type default)
			)
			(layer "F.Fab")
		)
		(fp_line
			(start 0.12065 -0.3048)
			(end 0.67945 -0.3048)
			(stroke
				(width 0.1)
				(type default)
			)
			(layer "F.Fab")
		)
		(fp_line
			(start 0.12065 -0.2794)
			(end 0.12065 -0.3048)
			(stroke
				(width 0.1)
				(type default)
			)
			(layer "F.Fab")
		)
		(fp_line
			(start -0.12065 -0.2794)
			(end 0.12065 -0.2794)
			(stroke
				(width 0.1)
				(type default)
			)
			(layer "F.Fab")
		)
		(fp_line
			(start 0.120396 0.2794)
			(end -0.12065 0.2794)
			(stroke
				(width 0.1)
				(type default)
			)
			(layer "F.Fab")
		)
		(fp_line
			(start -0.12065 0.2794)
			(end -0.12065 0.3048)
			(stroke
				(width 0.1)
				(type default)
			)
			(layer "F.Fab")
		)
		(fp_line
			(start 0.67945 0.3048)
			(end 0.120396 0.3048)
			(stroke
				(width 0.1)
				(type default)
			)
			(layer "F.Fab")
		)
		(fp_line
			(start 0.120396 0.3048)
			(end 0.120396 0.2794)
			(stroke
				(width 0.1)
				(type default)
			)
			(layer "F.Fab")
		)
		(fp_line
			(start -0.12065 0.3048)
			(end -0.67945 0.3048)
			(stroke
				(width 0.1)
				(type default)
			)
			(layer "F.Fab")
		)
		(fp_line
			(start -0.67945 0.3048)
			(end -0.67945 -0.305054)
			(stroke
				(width 0.1)
				(type default)
			)
			(layer "F.Fab")
		)
		(pad "1" smd circle
			(at -0.40005 0 90)
			(size 0 0)
			(layers "F.Cu" "F.Mask" "F.Paste")
			(net "JTAG_SCM_PLD_TDO")
		)
		(pad "2" smd circle
			(at 0.40005 0 90)
			(size 0 0)
			(layers "F.Cu" "F.Mask" "F.Paste")
			(net "JTAG_SCM_CONN_TDO")
		)
	)
	(footprint ""
		(layer "F.Cu")
		(at 49.2252 -28.2702)
		(property "Reference" "R433"
			(at 0 0 0)
			(layer "F.SilkS")
			(hide yes)
			(effects
				(font
					(size 1.27 1.27)
				)
			)
		)
		(property "Value" ""
			(at 0 0 0)
			(layer "F.Fab")
			(effects
				(font
					(size 1.27 1.27)
				)
			)
		)
		(duplicate_pad_numbers_are_jumpers no)
		(fp_line
			(start -0.7874 -0.4064)
			(end 0.7874 -0.4064)
			(stroke
				(width 0.1524)
				(type default)
			)
			(layer "F.SilkS")
		)
		(fp_line
			(start -0.7874 0.4064)
			(end -0.7874 -0.4064)
			(stroke
				(width 0.1524)
				(type default)
			)
			(layer "F.SilkS")
		)
		(fp_line
			(start 0.7874 -0.4064)
			(end 0.7874 0.4064)
			(stroke
				(width 0.1524)
				(type default)
			)
			(layer "F.SilkS")
		)
		(fp_line
			(start 0.7874 0.4064)
			(end -0.7874 0.4064)
			(stroke
				(width 0.1524)
				(type default)
			)
			(layer "F.SilkS")
		)
		(fp_line
			(start -0.67945 -0.305054)
			(end -0.12065 -0.305054)
			(stroke
				(width 0.1)
				(type default)
			)
			(layer "F.Fab")
		)
		(fp_line
			(start -0.67945 0.3048)
			(end -0.67945 -0.305054)
			(stroke
				(width 0.1)
				(type default)
			)
			(layer "F.Fab")
		)
		(fp_line
			(start -0.12065 -0.305054)
			(end -0.12065 -0.2794)
			(stroke
				(width 0.1)
				(type default)
			)
			(layer "F.Fab")
		)
		(fp_line
			(start -0.12065 -0.2794)
			(end 0.12065 -0.2794)
			(stroke
				(width 0.1)
				(type default)
			)
			(layer "F.Fab")
		)
		(fp_line
			(start -0.12065 0.2794)
			(end -0.12065 0.3048)
			(stroke
				(width 0.1)
				(type default)
			)
			(layer "F.Fab")
		)
		(fp_line
			(start -0.12065 0.3048)
			(end -0.67945 0.3048)
			(stroke
				(width 0.1)
				(type default)
			)
			(layer "F.Fab")
		)
		(fp_line
			(start 0.120396 0.2794)
			(end -0.12065 0.2794)
			(stroke
				(width 0.1)
				(type default)
			)
			(layer "F.Fab")
		)
		(fp_line
			(start 0.120396 0.3048)
			(end 0.120396 0.2794)
			(stroke
				(width 0.1)
				(type default)
			)
			(layer "F.Fab")
		)
		(fp_line
			(start 0.12065 -0.3048)
			(end 0.67945 -0.3048)
			(stroke
				(width 0.1)
				(type default)
			)
			(layer "F.Fab")
		)
		(fp_line
			(start 0.12065 -0.2794)
			(end 0.12065 -0.3048)
			(stroke
				(width 0.1)
				(type default)
			)
			(layer "F.Fab")
		)
		(fp_line
			(start 0.67945 -0.3048)
			(end 0.67945 0.3048)
			(stroke
				(width 0.1)
				(type default)
			)
			(layer "F.Fab")
		)
		(fp_line
			(start 0.67945 0.3048)
			(end 0.120396 0.3048)
			(stroke
				(width 0.1)
				(type default)
			)
			(layer "F.Fab")
		)
		(pad "1" smd circle
			(at -0.40005 0)
			(size 0 0)
			(layers "F.Cu" "F.Mask" "F.Paste")
			(net "SGPIO_DI_1")
		)
		(pad "2" smd circle
			(at 0.40005 0)
			(size 0 0)
			(layers "F.Cu" "F.Mask" "F.Paste")
			(net "SGPIO_BMC_M1_DI")
		)
	)
	(footprint ""
		(layer "F.Cu")
		(at 57.531 -102.9462 -90)
		(property "Reference" "R859"
			(at 0 0 270)
			(layer "F.SilkS")
			(hide yes)
			(effects
				(font
					(size 1.27 1.27)
				)
			)
		)
		(property "Value" ""
			(at 0 0 270)
			(layer "F.Fab")
			(effects
				(font
					(size 1.27 1.27)
				)
			)
		)
		(duplicate_pad_numbers_are_jumpers no)
		(fp_line
			(start -0.7874 0.4064)
			(end -0.7874 -0.4064)
			(stroke
				(width 0.1524)
				(type default)
			)
			(layer "F.SilkS")
		)
		(fp_line
			(start 0.7874 0.4064)
			(end -0.7874 0.4064)
			(stroke
				(width 0.1524)
				(type default)
			)
			(layer "F.SilkS")
		)
		(fp_line
			(start -0.7874 -0.4064)
			(end 0.7874 -0.4064)
			(stroke
				(width 0.1524)
				(type default)
			)
			(layer "F.SilkS")
		)
		(fp_line
			(start 0.7874 -0.4064)
			(end 0.7874 0.4064)
			(stroke
				(width 0.1524)
				(type default)
			)
			(layer "F.SilkS")
		)
		(fp_line
			(start -0.67945 0.3048)
			(end -0.67945 -0.305054)
			(stroke
				(width 0.1)
				(type default)
			)
			(layer "F.Fab")
		)
		(fp_line
			(start -0.12065 0.3048)
			(end -0.67945 0.3048)
			(stroke
				(width 0.1)
				(type default)
			)
			(layer "F.Fab")
		)
		(fp_line
			(start 0.120396 0.3048)
			(end 0.120396 0.2794)
			(stroke
				(width 0.1)
				(type default)
			)
			(layer "F.Fab")
		)
		(fp_line
			(start 0.67945 0.3048)
			(end 0.120396 0.3048)
			(stroke
				(width 0.1)
				(type default)
			)
			(layer "F.Fab")
		)
		(fp_line
			(start -0.12065 0.2794)
			(end -0.12065 0.3048)
			(stroke
				(width 0.1)
				(type default)
			)
			(layer "F.Fab")
		)
		(fp_line
			(start 0.120396 0.2794)
			(end -0.12065 0.2794)
			(stroke
				(width 0.1)
				(type default)
			)
			(layer "F.Fab")
		)
		(fp_line
			(start -0.12065 -0.2794)
			(end 0.12065 -0.2794)
			(stroke
				(width 0.1)
				(type default)
			)
			(layer "F.Fab")
		)
		(fp_line
			(start 0.12065 -0.2794)
			(end 0.12065 -0.3048)
			(stroke
				(width 0.1)
				(type default)
			)
			(layer "F.Fab")
		)
		(fp_line
			(start 0.12065 -0.3048)
			(end 0.67945 -0.3048)
			(stroke
				(width 0.1)
				(type default)
			)
			(layer "F.Fab")
		)
		(fp_line
			(start 0.67945 -0.3048)
			(end 0.67945 0.3048)
			(stroke
				(width 0.1)
				(type default)
			)
			(layer "F.Fab")
		)
		(fp_line
			(start -0.67945 -0.305054)
			(end -0.12065 -0.305054)
			(stroke
				(width 0.1)
				(type default)
			)
			(layer "F.Fab")
		)
		(fp_line
			(start -0.12065 -0.305054)
			(end -0.12065 -0.2794)
			(stroke
				(width 0.1)
				(type default)
			)
			(layer "F.Fab")
		)
		(pad "1" smd circle
			(at -0.40005 0 270)
			(size 0 0)
			(layers "F.Cu" "F.Mask" "F.Paste")
			(net "SPI_SYS_R_CLK")
		)
		(pad "2" smd circle
			(at 0.40005 0 270)
			(size 0 0)
			(layers "F.Cu" "F.Mask" "F.Paste")
			(net "SPI_SYS_MUX_CLK")
		)
	)
	(footprint ""
		(layer "F.Cu")
		(at 84.201 -30.099)
		(property "Reference" "C288"
			(at 0 0 0)
			(layer "F.SilkS")
			(hide yes)
			(effects
				(font
					(size 1.27 1.27)
				)
			)
		)
		(property "Value" ""
			(at 0 0 0)
			(layer "F.Fab")
			(effects
				(font
					(size 1.27 1.27)
				)
			)
		)
		(duplicate_pad_numbers_are_jumpers no)
		(fp_line
			(start -1.651 -0.8382)
			(end 1.651 -0.8382)
			(stroke
				(width 0.1524)
				(type default)
			)
			(layer "F.SilkS")
		)
		(fp_line
			(start -1.651 0.8382)
			(end -1.651 -0.8382)
			(stroke
				(width 0.1524)
				(type default)
			)
			(layer "F.SilkS")
		)
		(fp_line
			(start 0 0.8382)
			(end 0 -0.8382)
			(stroke
				(width 0.1524)
				(type default)
			)
			(layer "F.SilkS")
		)
		(fp_line
			(start 1.651 -0.8382)
			(end 1.651 0.8382)
			(stroke
				(width 0.1524)
				(type default)
			)
			(layer "F.SilkS")
		)
		(fp_line
			(start 1.651 0.8382)
			(end -1.651 0.8382)
			(stroke
				(width 0.1524)
				(type default)
			)
			(layer "F.SilkS")
		)
		(fp_line
			(start -1.55956 -0.7366)
			(end -1.55956 0.7366)
			(stroke
				(width 0.1)
				(type default)
			)
			(layer "F.Fab")
		)
		(fp_line
			(start -1.55956 0.7366)
			(end -1.524 0.7366)
			(stroke
				(width 0.1)
				(type default)
			)
			(layer "F.Fab")
		)
		(fp_line
			(start -1.524 -0.7366)
			(end -1.55956 -0.7366)
			(stroke
				(width 0.1)
				(type default)
			)
			(layer "F.Fab")
		)
		(fp_line
			(start -1.524 0.7366)
			(end 1.524 0.7366)
			(stroke
				(width 0.1)
				(type default)
			)
			(layer "F.Fab")
		)
		(fp_line
			(start 1.524 -0.7366)
			(end -1.524 -0.7366)
			(stroke
				(width 0.1)
				(type default)
			)
			(layer "F.Fab")
		)
		(fp_line
			(start 1.524 0.7366)
			(end 1.55956 0.7366)
			(stroke
				(width 0.1)
				(type default)
			)
			(layer "F.Fab")
		)
		(fp_line
			(start 1.55956 -0.7366)
			(end 1.524 -0.7366)
			(stroke
				(width 0.1)
				(type default)
			)
			(layer "F.Fab")
		)
		(fp_line
			(start 1.55956 0.7366)
			(end 1.55956 -0.7366)
			(stroke
				(width 0.1)
				(type default)
			)
			(layer "F.Fab")
		)
		(pad "1" smd rect
			(at -0.94996 0 180)
			(size 1.1176 1.3716)
			(layers "F.Cu" "F.Mask" "F.Paste")
			(net "P3V3_AUX")
		)
		(pad "2" smd rect
			(at 0.94996 0 180)
			(size 1.1176 1.3716)
			(layers "F.Cu" "F.Mask" "F.Paste")
			(net "GND")
		)
	)
	(footprint ""
		(layer "F.Cu")
		(at 50.75174 -63.953644 90)
		(property "Reference" "R216"
			(at 0 0 90)
			(layer "F.SilkS")
			(hide yes)
			(effects
				(font
					(size 1.27 1.27)
				)
			)
		)
		(property "Value" ""
			(at 0 0 90)
			(layer "F.Fab")
			(effects
				(font
					(size 1.27 1.27)
				)
			)
		)
		(duplicate_pad_numbers_are_jumpers no)
		(fp_line
			(start 0.7874 -0.4064)
			(end 0.7874 0.4064)
			(stroke
				(width 0.1524)
				(type default)
			)
			(layer "F.SilkS")
		)
		(fp_line
			(start -0.7874 -0.4064)
			(end 0.7874 -0.4064)
			(stroke
				(width 0.1524)
				(type default)
			)
			(layer "F.SilkS")
		)
		(fp_line
			(start 0.7874 0.4064)
			(end -0.7874 0.4064)
			(stroke
				(width 0.1524)
				(type default)
			)
			(layer "F.SilkS")
		)
		(fp_line
			(start -0.7874 0.4064)
			(end -0.7874 -0.4064)
			(stroke
				(width 0.1524)
				(type default)
			)
			(layer "F.SilkS")
		)
		(fp_line
			(start -0.12065 -0.305054)
			(end -0.12065 -0.2794)
			(stroke
				(width 0.1)
				(type default)
			)
			(layer "F.Fab")
		)
		(fp_line
			(start -0.67945 -0.305054)
			(end -0.12065 -0.305054)
			(stroke
				(width 0.1)
				(type default)
			)
			(layer "F.Fab")
		)
		(fp_line
			(start 0.67945 -0.3048)
			(end 0.67945 0.3048)
			(stroke
				(width 0.1)
				(type default)
			)
			(layer "F.Fab")
		)
		(fp_line
			(start 0.12065 -0.3048)
			(end 0.67945 -0.3048)
			(stroke
				(width 0.1)
				(type default)
			)
			(layer "F.Fab")
		)
		(fp_line
			(start 0.12065 -0.2794)
			(end 0.12065 -0.3048)
			(stroke
				(width 0.1)
				(type default)
			)
			(layer "F.Fab")
		)
		(fp_line
			(start -0.12065 -0.2794)
			(end 0.12065 -0.2794)
			(stroke
				(width 0.1)
				(type default)
			)
			(layer "F.Fab")
		)
		(fp_line
			(start 0.120396 0.2794)
			(end -0.12065 0.2794)
			(stroke
				(width 0.1)
				(type default)
			)
			(layer "F.Fab")
		)
		(fp_line
			(start -0.12065 0.2794)
			(end -0.12065 0.3048)
			(stroke
				(width 0.1)
				(type default)
			)
			(layer "F.Fab")
		)
		(fp_line
			(start 0.67945 0.3048)
			(end 0.120396 0.3048)
			(stroke
				(width 0.1)
				(type default)
			)
			(layer "F.Fab")
		)
		(fp_line
			(start 0.120396 0.3048)
			(end 0.120396 0.2794)
			(stroke
				(width 0.1)
				(type default)
			)
			(layer "F.Fab")
		)
		(fp_line
			(start -0.12065 0.3048)
			(end -0.67945 0.3048)
			(stroke
				(width 0.1)
				(type default)
			)
			(layer "F.Fab")
		)
		(fp_line
			(start -0.67945 0.3048)
			(end -0.67945 -0.305054)
			(stroke
				(width 0.1)
				(type default)
			)
			(layer "F.Fab")
		)
		(pad "1" smd circle
			(at -0.40005 0 90)
			(size 0 0)
			(layers "F.Cu" "F.Mask" "F.Paste")
			(net "PECI_BMC_R")
		)
		(pad "2" smd circle
			(at 0.40005 0 90)
			(size 0 0)
			(layers "F.Cu" "F.Mask" "F.Paste")
			(net "PECI_BMC")
		)
	)
	(footprint ""
		(layer "F.Cu")
		(at 38.123876 -46.378876 180)
		(property "Reference" "R423"
			(at 0 0 180)
			(layer "F.SilkS")
			(hide yes)
			(effects
				(font
					(size 1.27 1.27)
				)
			)
		)
		(property "Value" ""
			(at 0 0 180)
			(layer "F.Fab")
			(effects
				(font
					(size 1.27 1.27)
				)
			)
		)
		(duplicate_pad_numbers_are_jumpers no)
		(fp_line
			(start 0.7874 0.4064)
			(end -0.7874 0.4064)
			(stroke
				(width 0.1524)
				(type default)
			)
			(layer "F.SilkS")
		)
		(fp_line
			(start 0.7874 -0.4064)
			(end 0.7874 0.4064)
			(stroke
				(width 0.1524)
				(type default)
			)
			(layer "F.SilkS")
		)
		(fp_line
			(start -0.7874 0.4064)
			(end -0.7874 -0.4064)
			(stroke
				(width 0.1524)
				(type default)
			)
			(layer "F.SilkS")
		)
		(fp_line
			(start -0.7874 -0.4064)
			(end 0.7874 -0.4064)
			(stroke
				(width 0.1524)
				(type default)
			)
			(layer "F.SilkS")
		)
		(fp_line
			(start 0.67945 0.3048)
			(end 0.120396 0.3048)
			(stroke
				(width 0.1)
				(type default)
			)
			(layer "F.Fab")
		)
		(fp_line
			(start 0.67945 -0.3048)
			(end 0.67945 0.3048)
			(stroke
				(width 0.1)
				(type default)
			)
			(layer "F.Fab")
		)
		(fp_line
			(start 0.12065 -0.2794)
			(end 0.12065 -0.3048)
			(stroke
				(width 0.1)
				(type default)
			)
			(layer "F.Fab")
		)
		(fp_line
			(start 0.12065 -0.3048)
			(end 0.67945 -0.3048)
			(stroke
				(width 0.1)
				(type default)
			)
			(layer "F.Fab")
		)
		(fp_line
			(start 0.120396 0.3048)
			(end 0.120396 0.2794)
			(stroke
				(width 0.1)
				(type default)
			)
			(layer "F.Fab")
		)
		(fp_line
			(start 0.120396 0.2794)
			(end -0.12065 0.2794)
			(stroke
				(width 0.1)
				(type default)
			)
			(layer "F.Fab")
		)
		(fp_line
			(start -0.12065 0.3048)
			(end -0.67945 0.3048)
			(stroke
				(width 0.1)
				(type default)
			)
			(layer "F.Fab")
		)
		(fp_line
			(start -0.12065 0.2794)
			(end -0.12065 0.3048)
			(stroke
				(width 0.1)
				(type default)
			)
			(layer "F.Fab")
		)
		(fp_line
			(start -0.12065 -0.2794)
			(end 0.12065 -0.2794)
			(stroke
				(width 0.1)
				(type default)
			)
			(layer "F.Fab")
		)
		(fp_line
			(start -0.12065 -0.305054)
			(end -0.12065 -0.2794)
			(stroke
				(width 0.1)
				(type default)
			)
			(layer "F.Fab")
		)
		(fp_line
			(start -0.67945 0.3048)
			(end -0.67945 -0.305054)
			(stroke
				(width 0.1)
				(type default)
			)
			(layer "F.Fab")
		)
		(fp_line
			(start -0.67945 -0.305054)
			(end -0.12065 -0.305054)
			(stroke
				(width 0.1)
				(type default)
			)
			(layer "F.Fab")
		)
		(pad "1" smd circle
			(at -0.40005 0 180)
			(size 0 0)
			(layers "F.Cu" "F.Mask" "F.Paste")
			(net "SMB_BMC_MM13_R_SCL")
		)
		(pad "2" smd circle
			(at 0.40005 0 180)
			(size 0 0)
			(layers "F.Cu" "F.Mask" "F.Paste")
			(net "SMB_BMC_MM13_SCL")
		)
	)
)
